(kicad_pcb
	(version 20260206)
	(generator "pcbnew")
	(generator_version "10.0")
	(general
		(thickness 1.6)
		(legacy_teardrops no)
	)
	(paper "A4")
	(title_block
		(title "03242023_DA0F0TMBIJ0_F0T_Motherboard_J_brd_V01_OCP.brd")
		(comment 1 "Grand Teton / footprints 2881-2886 of 6105")
	)
	(layers
		(0 "F.Cu" signal "TOP")
		(4 "In1.Cu" signal "GND")
		(6 "In2.Cu" signal "IN1")
		(8 "In3.Cu" signal "GND1")
		(10 "In4.Cu" signal "IN2")
		(12 "In5.Cu" signal "GND2")
		(14 "In6.Cu" signal "IN3")
		(16 "In7.Cu" signal "GND3")
		(18 "In8.Cu" signal "VCC")
		(20 "In9.Cu" signal "VCC1")
		(22 "In10.Cu" signal "GND4")
		(24 "In11.Cu" signal "IN4")
		(26 "In12.Cu" signal "GND5")
		(28 "In13.Cu" signal "IN5")
		(30 "In14.Cu" signal "GND6")
		(32 "In15.Cu" signal "IN6")
		(34 "In16.Cu" signal "GND7")
		(2 "B.Cu" signal "BOTTOM")
		(9 "F.Adhes" user "F.Adhesive")
		(11 "B.Adhes" user "B.Adhesive")
		(13 "F.Paste" user "Package Geometry/Pastemask Top")
		(15 "B.Paste" user "Package Geometry/Pastemask Bottom")
		(5 "F.SilkS" user "Ref Des/Silkscreen Top")
		(7 "B.SilkS" user "Ref Des/Silkscreen Bottom")
		(1 "F.Mask" user "Board Geometry/Soldermask Top")
		(3 "B.Mask" user "Board Geometry/Soldermask Bottom")
		(17 "Dwgs.User" user "User.Drawings")
		(19 "Cmts.User" user "User.Comments")
		(21 "Eco1.User" user "User.Eco1")
		(23 "Eco2.User" user "User.Eco2")
		(25 "Edge.Cuts" user "Board Geometry/Outline")
		(27 "Margin" user)
		(31 "F.CrtYd" user "Package Geometry/Place Bound Top")
		(29 "B.CrtYd" user "Package Geometry/Place Bound Bottom")
		(35 "F.Fab" user "Ref Des/Assembly Top")
		(33 "B.Fab" user "Ref Des/Assembly Bottom")
	)
	(footprint ""
		(layer "F.Cu")
		(at 150.04796 -37.904166)
		(property "Reference" "Y9"
			(at -1.3462 -2.174748 0)
			(unlocked yes)
			(layer "F.SilkS")
			(effects
				(font
					(size 0.7874 0.5842)
					(thickness 0.1524)
				)
				(justify left)
			)
		)
		(property "Value" ""
			(at 0 0 0)
			(layer "F.Fab")
			(effects
				(font
					(size 1.27 1.27)
				)
			)
		)
		(duplicate_pad_numbers_are_jumpers no)
		(fp_line
			(start -1.2446 -1.4986)
			(end -1.2446 1.4986)
			(stroke
				(width 0.1524)
				(type default)
			)
			(layer "F.SilkS")
		)
		(fp_line
			(start -1.2446 1.4986)
			(end 1.2446 1.4986)
			(stroke
				(width 0.1524)
				(type default)
			)
			(layer "F.SilkS")
		)
		(fp_line
			(start 1.2446 -1.4986)
			(end -1.2446 -1.4986)
			(stroke
				(width 0.1524)
				(type default)
			)
			(layer "F.SilkS")
		)
		(fp_line
			(start 1.2446 1.4986)
			(end 1.2446 -1.4986)
			(stroke
				(width 0.1524)
				(type default)
			)
			(layer "F.SilkS")
		)
		(fp_poly
			(pts
				(xy -2.4638 -1.357884) (xy -1.4478 -0.849884) (xy -2.4638 -0.341884)
			)
			(stroke
				(width 0)
				(type default)
			)
			(fill yes)
			(layer "F.SilkS")
		)
		(fp_line
			(start -1.050036 -1.299972)
			(end -1.050036 1.299972)
			(stroke
				(width 0.1)
				(type default)
			)
			(layer "F.Fab")
		)
		(fp_line
			(start -1.050036 1.299972)
			(end 1.050036 1.299972)
			(stroke
				(width 0.1)
				(type default)
			)
			(layer "F.Fab")
		)
		(fp_line
			(start 1.050036 -1.299972)
			(end -1.050036 -1.299972)
			(stroke
				(width 0.1)
				(type default)
			)
			(layer "F.Fab")
		)
		(fp_line
			(start 1.050036 1.299972)
			(end 1.050036 -1.299972)
			(stroke
				(width 0.1)
				(type default)
			)
			(layer "F.Fab")
		)
		(fp_poly
			(pts
				(xy -2.4638 -1.357884) (xy -2.4638 -0.341884) (xy -1.4478 -0.849884)
			)
			(stroke
				(width 0)
				(type default)
			)
			(fill yes)
			(layer "F.Fab")
		)
		(pad "1" smd rect
			(at -0.649986 -0.849884 180)
			(size 0.9144 1.016)
			(layers "F.Cu" "F.Mask" "F.Paste")
			(net "USB_HUB_2_XTAL_IN")
		)
		(pad "2" smd rect
			(at -0.649986 0.849884 180)
			(size 0.9144 1.016)
			(layers "F.Cu" "F.Mask" "F.Paste")
			(net "GND")
		)
		(pad "3" smd rect
			(at 0.649986 0.849884 180)
			(size 0.9144 1.016)
			(layers "F.Cu" "F.Mask" "F.Paste")
			(net "USB_HUB_2_XTAL_OUT")
		)
		(pad "4" smd rect
			(at 0.649986 -0.849884 180)
			(size 0.9144 1.016)
			(layers "F.Cu" "F.Mask" "F.Paste")
			(net "GND")
		)
	)
	(footprint ""
		(layer "F.Cu")
		(at 366.48263 -256.654046 -90)
		(property "Reference" "C992"
			(at 0 0 270)
			(layer "F.SilkS")
			(hide yes)
			(effects
				(font
					(size 1.27 1.27)
				)
			)
		)
		(property "Value" ""
			(at 0 0 270)
			(layer "F.Fab")
			(effects
				(font
					(size 1.27 1.27)
				)
			)
		)
		(duplicate_pad_numbers_are_jumpers no)
		(fp_line
			(start -0.7874 0.4064)
			(end -0.7874 -0.4064)
			(stroke
				(width 0.1524)
				(type default)
			)
			(layer "F.SilkS")
		)
		(fp_line
			(start 0.7874 0.4064)
			(end -0.7874 0.4064)
			(stroke
				(width 0.1524)
				(type default)
			)
			(layer "F.SilkS")
		)
		(fp_line
			(start -0.7874 -0.4064)
			(end 0.7874 -0.4064)
			(stroke
				(width 0.1524)
				(type default)
			)
			(layer "F.SilkS")
		)
		(fp_line
			(start 0.7874 -0.4064)
			(end 0.7874 0.4064)
			(stroke
				(width 0.1524)
				(type default)
			)
			(layer "F.SilkS")
		)
		(fp_line
			(start -0.67945 0.3048)
			(end -0.67945 -0.305054)
			(stroke
				(width 0.1)
				(type default)
			)
			(layer "F.Fab")
		)
		(fp_line
			(start -0.12065 0.3048)
			(end -0.67945 0.3048)
			(stroke
				(width 0.1)
				(type default)
			)
			(layer "F.Fab")
		)
		(fp_line
			(start 0.120396 0.3048)
			(end 0.120396 0.2794)
			(stroke
				(width 0.1)
				(type default)
			)
			(layer "F.Fab")
		)
		(fp_line
			(start 0.67945 0.3048)
			(end 0.120396 0.3048)
			(stroke
				(width 0.1)
				(type default)
			)
			(layer "F.Fab")
		)
		(fp_line
			(start -0.12065 0.2794)
			(end -0.12065 0.3048)
			(stroke
				(width 0.1)
				(type default)
			)
			(layer "F.Fab")
		)
		(fp_line
			(start 0.120396 0.2794)
			(end -0.12065 0.2794)
			(stroke
				(width 0.1)
				(type default)
			)
			(layer "F.Fab")
		)
		(fp_line
			(start -0.12065 -0.2794)
			(end 0.12065 -0.2794)
			(stroke
				(width 0.1)
				(type default)
			)
			(layer "F.Fab")
		)
		(fp_line
			(start 0.12065 -0.2794)
			(end 0.12065 -0.3048)
			(stroke
				(width 0.1)
				(type default)
			)
			(layer "F.Fab")
		)
		(fp_line
			(start 0.12065 -0.3048)
			(end 0.67945 -0.3048)
			(stroke
				(width 0.1)
				(type default)
			)
			(layer "F.Fab")
		)
		(fp_line
			(start 0.67945 -0.3048)
			(end 0.67945 0.3048)
			(stroke
				(width 0.1)
				(type default)
			)
			(layer "F.Fab")
		)
		(fp_line
			(start -0.67945 -0.305054)
			(end -0.12065 -0.305054)
			(stroke
				(width 0.1)
				(type default)
			)
			(layer "F.Fab")
		)
		(fp_line
			(start -0.12065 -0.305054)
			(end -0.12065 -0.2794)
			(stroke
				(width 0.1)
				(type default)
			)
			(layer "F.Fab")
		)
		(pad "1" smd circle
			(at -0.40005 0 270)
			(size 0 0)
			(layers "F.Cu" "F.Mask" "F.Paste")
			(net "PVCCIN_CPU0")
		)
		(pad "2" smd circle
			(at 0.40005 0 270)
			(size 0 0)
			(layers "F.Cu" "F.Mask" "F.Paste")
			(net "GND")
		)
	)
	(footprint ""
		(layer "F.Cu")
		(at 200.03008 -131.694428 90)
		(property "Reference" "R2529"
			(at 0 0 90)
			(layer "F.SilkS")
			(hide yes)
			(effects
				(font
					(size 1.27 1.27)
				)
			)
		)
		(property "Value" ""
			(at 0 0 90)
			(layer "F.Fab")
			(effects
				(font
					(size 1.27 1.27)
				)
			)
		)
		(duplicate_pad_numbers_are_jumpers no)
		(fp_line
			(start 0.7874 -0.4064)
			(end 0.7874 0.4064)
			(stroke
				(width 0.1524)
				(type default)
			)
			(layer "F.SilkS")
		)
		(fp_line
			(start -0.7874 -0.4064)
			(end 0.7874 -0.4064)
			(stroke
				(width 0.1524)
				(type default)
			)
			(layer "F.SilkS")
		)
		(fp_line
			(start 0.7874 0.4064)
			(end -0.7874 0.4064)
			(stroke
				(width 0.1524)
				(type default)
			)
			(layer "F.SilkS")
		)
		(fp_line
			(start -0.7874 0.4064)
			(end -0.7874 -0.4064)
			(stroke
				(width 0.1524)
				(type default)
			)
			(layer "F.SilkS")
		)
		(fp_line
			(start -0.12065 -0.305054)
			(end -0.12065 -0.2794)
			(stroke
				(width 0.1)
				(type default)
			)
			(layer "F.Fab")
		)
		(fp_line
			(start -0.67945 -0.305054)
			(end -0.12065 -0.305054)
			(stroke
				(width 0.1)
				(type default)
			)
			(layer "F.Fab")
		)
		(fp_line
			(start 0.67945 -0.3048)
			(end 0.67945 0.3048)
			(stroke
				(width 0.1)
				(type default)
			)
			(layer "F.Fab")
		)
		(fp_line
			(start 0.12065 -0.3048)
			(end 0.67945 -0.3048)
			(stroke
				(width 0.1)
				(type default)
			)
			(layer "F.Fab")
		)
		(fp_line
			(start 0.12065 -0.2794)
			(end 0.12065 -0.3048)
			(stroke
				(width 0.1)
				(type default)
			)
			(layer "F.Fab")
		)
		(fp_line
			(start -0.12065 -0.2794)
			(end 0.12065 -0.2794)
			(stroke
				(width 0.1)
				(type default)
			)
			(layer "F.Fab")
		)
		(fp_line
			(start 0.120396 0.2794)
			(end -0.12065 0.2794)
			(stroke
				(width 0.1)
				(type default)
			)
			(layer "F.Fab")
		)
		(fp_line
			(start -0.12065 0.2794)
			(end -0.12065 0.3048)
			(stroke
				(width 0.1)
				(type default)
			)
			(layer "F.Fab")
		)
		(fp_line
			(start 0.67945 0.3048)
			(end 0.120396 0.3048)
			(stroke
				(width 0.1)
				(type default)
			)
			(layer "F.Fab")
		)
		(fp_line
			(start 0.120396 0.3048)
			(end 0.120396 0.2794)
			(stroke
				(width 0.1)
				(type default)
			)
			(layer "F.Fab")
		)
		(fp_line
			(start -0.12065 0.3048)
			(end -0.67945 0.3048)
			(stroke
				(width 0.1)
				(type default)
			)
			(layer "F.Fab")
		)
		(fp_line
			(start -0.67945 0.3048)
			(end -0.67945 -0.305054)
			(stroke
				(width 0.1)
				(type default)
			)
			(layer "F.Fab")
		)
		(pad "1" smd circle
			(at -0.40005 0 90)
			(size 0 0)
			(layers "F.Cu" "F.Mask" "F.Paste")
			(net "FM_P12V_HSC_EN_N")
		)
		(pad "2" smd circle
			(at 0.40005 0 90)
			(size 0 0)
			(layers "F.Cu" "F.Mask" "F.Paste")
			(net "FM_P12V_HSC_EN_R_N")
		)
	)
	(footprint ""
		(layer "F.Cu")
		(at 226.903788 -222.09887 180)
		(property "Reference" "R972"
			(at 0 0 180)
			(layer "F.SilkS")
			(hide yes)
			(effects
				(font
					(size 1.27 1.27)
				)
			)
		)
		(property "Value" ""
			(at 0 0 180)
			(layer "F.Fab")
			(effects
				(font
					(size 1.27 1.27)
				)
			)
		)
		(duplicate_pad_numbers_are_jumpers no)
		(fp_line
			(start 0.7874 0.4064)
			(end -0.7874 0.4064)
			(stroke
				(width 0.1524)
				(type default)
			)
			(layer "F.SilkS")
		)
		(fp_line
			(start 0.7874 -0.4064)
			(end 0.7874 0.4064)
			(stroke
				(width 0.1524)
				(type default)
			)
			(layer "F.SilkS")
		)
		(fp_line
			(start -0.7874 0.4064)
			(end -0.7874 -0.4064)
			(stroke
				(width 0.1524)
				(type default)
			)
			(layer "F.SilkS")
		)
		(fp_line
			(start -0.7874 -0.4064)
			(end 0.7874 -0.4064)
			(stroke
				(width 0.1524)
				(type default)
			)
			(layer "F.SilkS")
		)
		(fp_line
			(start 0.67945 0.3048)
			(end 0.120396 0.3048)
			(stroke
				(width 0.1)
				(type default)
			)
			(layer "F.Fab")
		)
		(fp_line
			(start 0.67945 -0.3048)
			(end 0.67945 0.3048)
			(stroke
				(width 0.1)
				(type default)
			)
			(layer "F.Fab")
		)
		(fp_line
			(start 0.12065 -0.2794)
			(end 0.12065 -0.3048)
			(stroke
				(width 0.1)
				(type default)
			)
			(layer "F.Fab")
		)
		(fp_line
			(start 0.12065 -0.3048)
			(end 0.67945 -0.3048)
			(stroke
				(width 0.1)
				(type default)
			)
			(layer "F.Fab")
		)
		(fp_line
			(start 0.120396 0.3048)
			(end 0.120396 0.2794)
			(stroke
				(width 0.1)
				(type default)
			)
			(layer "F.Fab")
		)
		(fp_line
			(start 0.120396 0.2794)
			(end -0.12065 0.2794)
			(stroke
				(width 0.1)
				(type default)
			)
			(layer "F.Fab")
		)
		(fp_line
			(start -0.12065 0.3048)
			(end -0.67945 0.3048)
			(stroke
				(width 0.1)
				(type default)
			)
			(layer "F.Fab")
		)
		(fp_line
			(start -0.12065 0.2794)
			(end -0.12065 0.3048)
			(stroke
				(width 0.1)
				(type default)
			)
			(layer "F.Fab")
		)
		(fp_line
			(start -0.12065 -0.2794)
			(end 0.12065 -0.2794)
			(stroke
				(width 0.1)
				(type default)
			)
			(layer "F.Fab")
		)
		(fp_line
			(start -0.12065 -0.305054)
			(end -0.12065 -0.2794)
			(stroke
				(width 0.1)
				(type default)
			)
			(layer "F.Fab")
		)
		(fp_line
			(start -0.67945 0.3048)
			(end -0.67945 -0.305054)
			(stroke
				(width 0.1)
				(type default)
			)
			(layer "F.Fab")
		)
		(fp_line
			(start -0.67945 -0.305054)
			(end -0.12065 -0.305054)
			(stroke
				(width 0.1)
				(type default)
			)
			(layer "F.Fab")
		)
		(pad "1" smd circle
			(at -0.40005 0 180)
			(size 0 0)
			(layers "F.Cu" "F.Mask" "F.Paste")
			(net "PVNN_TERM_CPU1")
		)
		(pad "2" smd circle
			(at 0.40005 0 180)
			(size 0 0)
			(layers "F.Cu" "F.Mask" "F.Paste")
			(net "SMB_S3M_CPU1_R_SDA")
		)
	)
	(footprint ""
		(layer "F.Cu")
		(at 96.141286 -427.776386 -90)
		(property "Reference" "R3525"
			(at 0 0 270)
			(layer "F.SilkS")
			(hide yes)
			(effects
				(font
					(size 1.27 1.27)
				)
			)
		)
		(property "Value" ""
			(at 0 0 270)
			(layer "F.Fab")
			(effects
				(font
					(size 1.27 1.27)
				)
			)
		)
		(duplicate_pad_numbers_are_jumpers no)
		(fp_line
			(start -0.7874 0.4064)
			(end -0.7874 -0.4064)
			(stroke
				(width 0.1524)
				(type default)
			)
			(layer "F.SilkS")
		)
		(fp_line
			(start 0.7874 0.4064)
			(end -0.7874 0.4064)
			(stroke
				(width 0.1524)
				(type default)
			)
			(layer "F.SilkS")
		)
		(fp_line
			(start -0.7874 -0.4064)
			(end 0.7874 -0.4064)
			(stroke
				(width 0.1524)
				(type default)
			)
			(layer "F.SilkS")
		)
		(fp_line
			(start 0.7874 -0.4064)
			(end 0.7874 0.4064)
			(stroke
				(width 0.1524)
				(type default)
			)
			(layer "F.SilkS")
		)
		(fp_line
			(start -0.67945 0.3048)
			(end -0.67945 -0.305054)
			(stroke
				(width 0.1)
				(type default)
			)
			(layer "F.Fab")
		)
		(fp_line
			(start -0.12065 0.3048)
			(end -0.67945 0.3048)
			(stroke
				(width 0.1)
				(type default)
			)
			(layer "F.Fab")
		)
		(fp_line
			(start 0.120396 0.3048)
			(end 0.120396 0.2794)
			(stroke
				(width 0.1)
				(type default)
			)
			(layer "F.Fab")
		)
		(fp_line
			(start 0.67945 0.3048)
			(end 0.120396 0.3048)
			(stroke
				(width 0.1)
				(type default)
			)
			(layer "F.Fab")
		)
		(fp_line
			(start -0.12065 0.2794)
			(end -0.12065 0.3048)
			(stroke
				(width 0.1)
				(type default)
			)
			(layer "F.Fab")
		)
		(fp_line
			(start 0.120396 0.2794)
			(end -0.12065 0.2794)
			(stroke
				(width 0.1)
				(type default)
			)
			(layer "F.Fab")
		)
		(fp_line
			(start -0.12065 -0.2794)
			(end 0.12065 -0.2794)
			(stroke
				(width 0.1)
				(type default)
			)
			(layer "F.Fab")
		)
		(fp_line
			(start 0.12065 -0.2794)
			(end 0.12065 -0.3048)
			(stroke
				(width 0.1)
				(type default)
			)
			(layer "F.Fab")
		)
		(fp_line
			(start 0.12065 -0.3048)
			(end 0.67945 -0.3048)
			(stroke
				(width 0.1)
				(type default)
			)
			(layer "F.Fab")
		)
		(fp_line
			(start 0.67945 -0.3048)
			(end 0.67945 0.3048)
			(stroke
				(width 0.1)
				(type default)
			)
			(layer "F.Fab")
		)
		(fp_line
			(start -0.67945 -0.305054)
			(end -0.12065 -0.305054)
			(stroke
				(width 0.1)
				(type default)
			)
			(layer "F.Fab")
		)
		(fp_line
			(start -0.12065 -0.305054)
			(end -0.12065 -0.2794)
			(stroke
				(width 0.1)
				(type default)
			)
			(layer "F.Fab")
		)
		(pad "1" smd circle
			(at -0.40005 0 270)
			(size 0 0)
			(layers "F.Cu" "F.Mask" "F.Paste")
			(net "P3V3_AUX")
		)
		(pad "2" smd circle
			(at 0.40005 0 270)
			(size 0 0)
			(layers "F.Cu" "F.Mask" "F.Paste")
			(net "GPU_FPGA_EROT_FATALERR_N")
		)
	)
	(footprint ""
		(layer "F.Cu")
		(at 106.584496 -70.78599)
		(property "Reference" "D78"
			(at -53.121306 50.178462 90)
			(unlocked yes)
			(layer "F.SilkS")
			(effects
				(font
					(size 0.635 0.4064)
					(thickness 0.1524)
				)
				(justify left)
			)
		)
		(property "Value" ""
			(at 0 0 0)
			(layer "F.Fab")
			(effects
				(font
					(size 1.27 1.27)
				)
			)
		)
		(duplicate_pad_numbers_are_jumpers no)
		(fp_line
			(start -0.90678 0.4826)
			(end -0.90678 -0.4699)
			(stroke
				(width 0.1524)
				(type default)
			)
			(layer "F.SilkS")
		)
		(fp_line
			(start -0.89408 -0.4826)
			(end 0.90678 -0.4826)
			(stroke
				(width 0.1524)
				(type default)
			)
			(layer "F.SilkS")
		)
		(fp_line
			(start -0.79248 -0.4826)
			(end 1.03378 -0.4826)
			(stroke
				(width 0.1524)
				(type default)
			)
			(layer "F.SilkS")
		)
		(fp_line
			(start -0.64008 -0.4826)
			(end 1.16078 -0.4826)
			(stroke
				(width 0.1524)
				(type default)
			)
			(layer "F.SilkS")
		)
		(fp_line
			(start 0.90678 -0.4826)
			(end 0.90678 0.4826)
			(stroke
				(width 0.1524)
				(type default)
			)
			(layer "F.SilkS")
		)
		(fp_line
			(start 0.90678 0.4826)
			(end -0.90678 0.4826)
			(stroke
				(width 0.1524)
				(type default)
			)
			(layer "F.SilkS")
		)
		(fp_line
			(start 1.03378 -0.4826)
			(end 1.03378 0.4826)
			(stroke
				(width 0.1524)
				(type default)
			)
			(layer "F.SilkS")
		)
		(fp_line
			(start 1.03378 0.4826)
			(end -0.79248 0.4826)
			(stroke
				(width 0.1524)
				(type default)
			)
			(layer "F.SilkS")
		)
		(fp_line
			(start 1.16078 -0.4826)
			(end 1.16078 0.4826)
			(stroke
				(width 0.1524)
				(type default)
			)
			(layer "F.SilkS")
		)
		(fp_line
			(start 1.16078 0.4826)
			(end -0.64008 0.4826)
			(stroke
				(width 0.1524)
				(type default)
			)
			(layer "F.SilkS")
		)
		(fp_line
			(start -0.499872 -0.249936)
			(end 0.499872 -0.249936)
			(stroke
				(width 0.1)
				(type default)
			)
			(layer "F.Fab")
		)
		(fp_line
			(start -0.499872 0.249936)
			(end -0.499872 -0.249936)
			(stroke
				(width 0.1)
				(type default)
			)
			(layer "F.Fab")
		)
		(fp_line
			(start 0.499872 -0.249936)
			(end 0.499872 0.249936)
			(stroke
				(width 0.1)
				(type default)
			)
			(layer "F.Fab")
		)
		(fp_line
			(start 0.499872 0.249936)
			(end -0.499872 0.249936)
			(stroke
				(width 0.1)
				(type default)
			)
			(layer "F.Fab")
		)
		(pad "A" smd rect
			(at -0.47498 0)
			(size 0.6096 0.7112)
			(layers "F.Cu" "F.Mask" "F.Paste")
			(net "LED_PWRGD_PVNN_MAIN_CPU0")
		)
		(pad "C" smd rect
			(at 0.47498 0)
			(size 0.6096 0.7112)
			(layers "F.Cu" "F.Mask" "F.Paste")
			(net "LED_PWRGD_PVNN_MAIN_CPU0_D")
		)
	)
)
